(kicad_pcb
	(version 20260206)
	(generator "pcbnew")
	(generator_version "10.0")
	(general
		(thickness 1.6)
		(legacy_teardrops no)
	)
	(paper "A4")
	(title_block
		(title "04192023_DAF0TMB3IC0_F0TG_MB_C_brd_V02_OCP.brd")
		(comment 1 "Grand Teton / footprints 7747-7753 of 8354")
	)
	(layers
		(0 "F.Cu" signal "TOP")
		(4 "In1.Cu" signal "GND")
		(6 "In2.Cu" signal "IN1")
		(8 "In3.Cu" signal "GND1")
		(10 "In4.Cu" signal "IN2")
		(12 "In5.Cu" signal "GND2")
		(14 "In6.Cu" signal "IN3")
		(16 "In7.Cu" signal "GND3")
		(18 "In8.Cu" signal "VCC")
		(20 "In9.Cu" signal "VCC1")
		(22 "In10.Cu" signal "GND4")
		(24 "In11.Cu" signal "IN4")
		(26 "In12.Cu" signal "GND5")
		(28 "In13.Cu" signal "IN5")
		(30 "In14.Cu" signal "GND6")
		(32 "In15.Cu" signal "IN6")
		(34 "In16.Cu" signal "GND7")
		(2 "B.Cu" signal "BOTTOM")
		(9 "F.Adhes" user "F.Adhesive")
		(11 "B.Adhes" user "B.Adhesive")
		(13 "F.Paste" user "Package Geometry/Pastemask Top")
		(15 "B.Paste" user "Package Geometry/Pastemask Bottom")
		(5 "F.SilkS" user "Ref Des/Silkscreen Top")
		(7 "B.SilkS" user "Ref Des/Silkscreen Bottom")
		(1 "F.Mask" user "Board Geometry/Soldermask Top")
		(3 "B.Mask" user "Board Geometry/Soldermask Bottom")
		(17 "Dwgs.User" user "User.Drawings")
		(19 "Cmts.User" user "User.Comments")
		(21 "Eco1.User" user "User.Eco1")
		(23 "Eco2.User" user "User.Eco2")
		(25 "Edge.Cuts" user "Board Geometry/Outline")
		(27 "Margin" user)
		(31 "F.CrtYd" user "Package Geometry/Place Bound Top")
		(29 "B.CrtYd" user "Package Geometry/Place Bound Bottom")
		(35 "F.Fab" user "Ref Des/Assembly Top")
		(33 "B.Fab" user "Ref Des/Assembly Bottom")
	)
	(footprint ""
		(layer "B.Cu")
		(at 182.468774 -133.843014 90)
		(property "Reference" "R6793"
			(at 0 0 90)
			(layer "B.SilkS")
			(hide yes)
			(effects
				(font
					(size 1.27 1.27)
				)
				(justify mirror)
			)
		)
		(property "Value" ""
			(at 0 0 90)
			(layer "B.Fab")
			(effects
				(font
					(size 1.27 1.27)
				)
				(justify mirror)
			)
		)
		(duplicate_pad_numbers_are_jumpers no)
		(fp_line
			(start 0.7874 -0.4064)
			(end -0.7874 -0.4064)
			(stroke
				(width 0.1524)
				(type default)
			)
			(layer "B.SilkS")
		)
		(fp_line
			(start -0.7874 -0.4064)
			(end -0.7874 0.4064)
			(stroke
				(width 0.1524)
				(type default)
			)
			(layer "B.SilkS")
		)
		(fp_line
			(start 0.7874 0.4064)
			(end 0.7874 -0.4064)
			(stroke
				(width 0.1524)
				(type default)
			)
			(layer "B.SilkS")
		)
		(fp_line
			(start -0.7874 0.4064)
			(end 0.7874 0.4064)
			(stroke
				(width 0.1524)
				(type default)
			)
			(layer "B.SilkS")
		)
		(fp_line
			(start 0.67945 -0.305054)
			(end 0.12065 -0.305054)
			(stroke
				(width 0.1)
				(type default)
			)
			(layer "B.Fab")
		)
		(fp_line
			(start 0.12065 -0.305054)
			(end 0.12065 -0.2794)
			(stroke
				(width 0.1)
				(type default)
			)
			(layer "B.Fab")
		)
		(fp_line
			(start -0.12065 -0.3048)
			(end -0.67945 -0.3048)
			(stroke
				(width 0.1)
				(type default)
			)
			(layer "B.Fab")
		)
		(fp_line
			(start -0.67945 -0.3048)
			(end -0.67945 0.3048)
			(stroke
				(width 0.1)
				(type default)
			)
			(layer "B.Fab")
		)
		(fp_line
			(start 0.12065 -0.2794)
			(end -0.12065 -0.2794)
			(stroke
				(width 0.1)
				(type default)
			)
			(layer "B.Fab")
		)
		(fp_line
			(start -0.12065 -0.2794)
			(end -0.12065 -0.3048)
			(stroke
				(width 0.1)
				(type default)
			)
			(layer "B.Fab")
		)
		(fp_line
			(start 0.12065 0.2794)
			(end 0.12065 0.3048)
			(stroke
				(width 0.1)
				(type default)
			)
			(layer "B.Fab")
		)
		(fp_line
			(start -0.120396 0.2794)
			(end 0.12065 0.2794)
			(stroke
				(width 0.1)
				(type default)
			)
			(layer "B.Fab")
		)
		(fp_line
			(start 0.67945 0.3048)
			(end 0.67945 -0.305054)
			(stroke
				(width 0.1)
				(type default)
			)
			(layer "B.Fab")
		)
		(fp_line
			(start 0.12065 0.3048)
			(end 0.67945 0.3048)
			(stroke
				(width 0.1)
				(type default)
			)
			(layer "B.Fab")
		)
		(fp_line
			(start -0.120396 0.3048)
			(end -0.120396 0.2794)
			(stroke
				(width 0.1)
				(type default)
			)
			(layer "B.Fab")
		)
		(fp_line
			(start -0.67945 0.3048)
			(end -0.120396 0.3048)
			(stroke
				(width 0.1)
				(type default)
			)
			(layer "B.Fab")
		)
		(pad "1" smd circle
			(at 0.40005 0 270)
			(size 0 0)
			(layers "B.Cu" "B.Mask" "B.Paste")
			(net "RST_RT_CPU1_P2_RESET_R_N")
		)
		(pad "2" smd circle
			(at -0.40005 0 270)
			(size 0 0)
			(layers "B.Cu" "B.Mask" "B.Paste")
			(net "RST_RT_CPU1_P2_RESET_R2_N")
		)
	)
	(footprint ""
		(layer "B.Cu")
		(at 185.680858 -147.837144 180)
		(property "Reference" "R8034"
			(at 0 0 0)
			(layer "B.SilkS")
			(hide yes)
			(effects
				(font
					(size 1.27 1.27)
				)
				(justify mirror)
			)
		)
		(property "Value" ""
			(at 0 0 0)
			(layer "B.Fab")
			(effects
				(font
					(size 1.27 1.27)
				)
				(justify mirror)
			)
		)
		(duplicate_pad_numbers_are_jumpers no)
		(fp_line
			(start 0.7874 0.4064)
			(end 0.7874 -0.4064)
			(stroke
				(width 0.1524)
				(type default)
			)
			(layer "B.SilkS")
		)
		(fp_line
			(start 0.7874 -0.4064)
			(end -0.7874 -0.4064)
			(stroke
				(width 0.1524)
				(type default)
			)
			(layer "B.SilkS")
		)
		(fp_line
			(start -0.7874 0.4064)
			(end 0.7874 0.4064)
			(stroke
				(width 0.1524)
				(type default)
			)
			(layer "B.SilkS")
		)
		(fp_line
			(start -0.7874 -0.4064)
			(end -0.7874 0.4064)
			(stroke
				(width 0.1524)
				(type default)
			)
			(layer "B.SilkS")
		)
		(fp_line
			(start 0.67945 0.3048)
			(end 0.67945 -0.305054)
			(stroke
				(width 0.1)
				(type default)
			)
			(layer "B.Fab")
		)
		(fp_line
			(start 0.67945 -0.305054)
			(end 0.12065 -0.305054)
			(stroke
				(width 0.1)
				(type default)
			)
			(layer "B.Fab")
		)
		(fp_line
			(start 0.12065 0.3048)
			(end 0.67945 0.3048)
			(stroke
				(width 0.1)
				(type default)
			)
			(layer "B.Fab")
		)
		(fp_line
			(start 0.12065 0.2794)
			(end 0.12065 0.3048)
			(stroke
				(width 0.1)
				(type default)
			)
			(layer "B.Fab")
		)
		(fp_line
			(start 0.12065 -0.2794)
			(end -0.12065 -0.2794)
			(stroke
				(width 0.1)
				(type default)
			)
			(layer "B.Fab")
		)
		(fp_line
			(start 0.12065 -0.305054)
			(end 0.12065 -0.2794)
			(stroke
				(width 0.1)
				(type default)
			)
			(layer "B.Fab")
		)
		(fp_line
			(start -0.120396 0.3048)
			(end -0.120396 0.2794)
			(stroke
				(width 0.1)
				(type default)
			)
			(layer "B.Fab")
		)
		(fp_line
			(start -0.120396 0.2794)
			(end 0.12065 0.2794)
			(stroke
				(width 0.1)
				(type default)
			)
			(layer "B.Fab")
		)
		(fp_line
			(start -0.12065 -0.2794)
			(end -0.12065 -0.3048)
			(stroke
				(width 0.1)
				(type default)
			)
			(layer "B.Fab")
		)
		(fp_line
			(start -0.12065 -0.3048)
			(end -0.67945 -0.3048)
			(stroke
				(width 0.1)
				(type default)
			)
			(layer "B.Fab")
		)
		(fp_line
			(start -0.67945 0.3048)
			(end -0.120396 0.3048)
			(stroke
				(width 0.1)
				(type default)
			)
			(layer "B.Fab")
		)
		(fp_line
			(start -0.67945 -0.3048)
			(end -0.67945 0.3048)
			(stroke
				(width 0.1)
				(type default)
			)
			(layer "B.Fab")
		)
		(pad "1" smd circle
			(at 0.40005 0)
			(size 0 0)
			(layers "B.Cu" "B.Mask" "B.Paste")
			(net "ESPI_CPU0_ALERT_R1_N")
		)
		(pad "2" smd circle
			(at -0.40005 0)
			(size 0 0)
			(layers "B.Cu" "B.Mask" "B.Paste")
			(net "ESPI_CPU0_ALERT_N")
		)
	)
	(footprint ""
		(layer "B.Cu")
		(at 383.732278 -144.647158 -90)
		(property "Reference" "PC464"
			(at 0 0 90)
			(layer "B.SilkS")
			(hide yes)
			(effects
				(font
					(size 1.27 1.27)
				)
				(justify mirror)
			)
		)
		(property "Value" ""
			(at 0 0 90)
			(layer "B.Fab")
			(effects
				(font
					(size 1.27 1.27)
				)
				(justify mirror)
			)
		)
		(duplicate_pad_numbers_are_jumpers no)
		(fp_line
			(start -0.7874 0.4064)
			(end 0.7874 0.4064)
			(stroke
				(width 0.1524)
				(type default)
			)
			(layer "B.SilkS")
		)
		(fp_line
			(start 0.7874 0.4064)
			(end 0.7874 -0.4064)
			(stroke
				(width 0.1524)
				(type default)
			)
			(layer "B.SilkS")
		)
		(fp_line
			(start -0.7874 -0.4064)
			(end -0.7874 0.4064)
			(stroke
				(width 0.1524)
				(type default)
			)
			(layer "B.SilkS")
		)
		(fp_line
			(start 0.7874 -0.4064)
			(end -0.7874 -0.4064)
			(stroke
				(width 0.1524)
				(type default)
			)
			(layer "B.SilkS")
		)
		(fp_line
			(start -0.67945 0.3048)
			(end -0.120396 0.3048)
			(stroke
				(width 0.1)
				(type default)
			)
			(layer "B.Fab")
		)
		(fp_line
			(start -0.120396 0.3048)
			(end -0.120396 0.2794)
			(stroke
				(width 0.1)
				(type default)
			)
			(layer "B.Fab")
		)
		(fp_line
			(start 0.12065 0.3048)
			(end 0.67945 0.3048)
			(stroke
				(width 0.1)
				(type default)
			)
			(layer "B.Fab")
		)
		(fp_line
			(start 0.67945 0.3048)
			(end 0.67945 -0.305054)
			(stroke
				(width 0.1)
				(type default)
			)
			(layer "B.Fab")
		)
		(fp_line
			(start -0.120396 0.2794)
			(end 0.12065 0.2794)
			(stroke
				(width 0.1)
				(type default)
			)
			(layer "B.Fab")
		)
		(fp_line
			(start 0.12065 0.2794)
			(end 0.12065 0.3048)
			(stroke
				(width 0.1)
				(type default)
			)
			(layer "B.Fab")
		)
		(fp_line
			(start -0.12065 -0.2794)
			(end -0.12065 -0.3048)
			(stroke
				(width 0.1)
				(type default)
			)
			(layer "B.Fab")
		)
		(fp_line
			(start 0.12065 -0.2794)
			(end -0.12065 -0.2794)
			(stroke
				(width 0.1)
				(type default)
			)
			(layer "B.Fab")
		)
		(fp_line
			(start -0.67945 -0.3048)
			(end -0.67945 0.3048)
			(stroke
				(width 0.1)
				(type default)
			)
			(layer "B.Fab")
		)
		(fp_line
			(start -0.12065 -0.3048)
			(end -0.67945 -0.3048)
			(stroke
				(width 0.1)
				(type default)
			)
			(layer "B.Fab")
		)
		(fp_line
			(start 0.12065 -0.305054)
			(end 0.12065 -0.2794)
			(stroke
				(width 0.1)
				(type default)
			)
			(layer "B.Fab")
		)
		(fp_line
			(start 0.67945 -0.305054)
			(end 0.12065 -0.305054)
			(stroke
				(width 0.1)
				(type default)
			)
			(layer "B.Fab")
		)
		(pad "1" smd circle
			(at 0.40005 0 90)
			(size 0 0)
			(layers "B.Cu" "B.Mask" "B.Paste")
			(net "VSENSE_PVDDCR_SOC_P0_VSEN1")
		)
		(pad "2" smd circle
			(at -0.40005 0 90)
			(size 0 0)
			(layers "B.Cu" "B.Mask" "B.Paste")
			(net "VSENSE_VSS_SENSE_A_P0")
		)
	)
	(footprint ""
		(layer "B.Cu")
		(at 102.938834 -250.892564 180)
		(property "Reference" "C2348"
			(at 0 0 0)
			(layer "B.SilkS")
			(hide yes)
			(effects
				(font
					(size 1.27 1.27)
				)
				(justify mirror)
			)
		)
		(property "Value" ""
			(at 0 0 0)
			(layer "B.Fab")
			(effects
				(font
					(size 1.27 1.27)
				)
				(justify mirror)
			)
		)
		(duplicate_pad_numbers_are_jumpers no)
		(fp_line
			(start 0.7874 0.4064)
			(end 0.7874 -0.4064)
			(stroke
				(width 0.1524)
				(type default)
			)
			(layer "B.SilkS")
		)
		(fp_line
			(start 0.7874 -0.4064)
			(end -0.7874 -0.4064)
			(stroke
				(width 0.1524)
				(type default)
			)
			(layer "B.SilkS")
		)
		(fp_line
			(start -0.7874 0.4064)
			(end 0.7874 0.4064)
			(stroke
				(width 0.1524)
				(type default)
			)
			(layer "B.SilkS")
		)
		(fp_line
			(start -0.7874 -0.4064)
			(end -0.7874 0.4064)
			(stroke
				(width 0.1524)
				(type default)
			)
			(layer "B.SilkS")
		)
		(fp_line
			(start 0.67945 0.3048)
			(end 0.67945 -0.305054)
			(stroke
				(width 0.1)
				(type default)
			)
			(layer "B.Fab")
		)
		(fp_line
			(start 0.67945 -0.305054)
			(end 0.12065 -0.305054)
			(stroke
				(width 0.1)
				(type default)
			)
			(layer "B.Fab")
		)
		(fp_line
			(start 0.12065 0.3048)
			(end 0.67945 0.3048)
			(stroke
				(width 0.1)
				(type default)
			)
			(layer "B.Fab")
		)
		(fp_line
			(start 0.12065 0.2794)
			(end 0.12065 0.3048)
			(stroke
				(width 0.1)
				(type default)
			)
			(layer "B.Fab")
		)
		(fp_line
			(start 0.12065 -0.2794)
			(end -0.12065 -0.2794)
			(stroke
				(width 0.1)
				(type default)
			)
			(layer "B.Fab")
		)
		(fp_line
			(start 0.12065 -0.305054)
			(end 0.12065 -0.2794)
			(stroke
				(width 0.1)
				(type default)
			)
			(layer "B.Fab")
		)
		(fp_line
			(start -0.120396 0.3048)
			(end -0.120396 0.2794)
			(stroke
				(width 0.1)
				(type default)
			)
			(layer "B.Fab")
		)
		(fp_line
			(start -0.120396 0.2794)
			(end 0.12065 0.2794)
			(stroke
				(width 0.1)
				(type default)
			)
			(layer "B.Fab")
		)
		(fp_line
			(start -0.12065 -0.2794)
			(end -0.12065 -0.3048)
			(stroke
				(width 0.1)
				(type default)
			)
			(layer "B.Fab")
		)
		(fp_line
			(start -0.12065 -0.3048)
			(end -0.67945 -0.3048)
			(stroke
				(width 0.1)
				(type default)
			)
			(layer "B.Fab")
		)
		(fp_line
			(start -0.67945 0.3048)
			(end -0.120396 0.3048)
			(stroke
				(width 0.1)
				(type default)
			)
			(layer "B.Fab")
		)
		(fp_line
			(start -0.67945 -0.3048)
			(end -0.67945 0.3048)
			(stroke
				(width 0.1)
				(type default)
			)
			(layer "B.Fab")
		)
		(pad "1" smd circle
			(at 0.40005 0)
			(size 0 0)
			(layers "B.Cu" "B.Mask" "B.Paste")
			(net "PVDDCR_CPU0_P1")
		)
		(pad "2" smd circle
			(at -0.40005 0)
			(size 0 0)
			(layers "B.Cu" "B.Mask" "B.Paste")
			(net "GND")
		)
	)
	(footprint ""
		(layer "B.Cu")
		(at 438.903618 -343.656412 -90)
		(property "Reference" "PC800"
			(at 7.654036 -3.431286 270)
			(unlocked yes)
			(layer "B.SilkS")
			(effects
				(font
					(size 0.7874 0.5842)
					(thickness 0.1524)
				)
				(justify left mirror)
			)
		)
		(property "Value" ""
			(at 0 0 90)
			(layer "B.Fab")
			(effects
				(font
					(size 1.27 1.27)
				)
				(justify mirror)
			)
		)
		(duplicate_pad_numbers_are_jumpers no)
		(fp_line
			(start -4.533392 2.249932)
			(end 4.533392 2.249932)
			(stroke
				(width 0.1524)
				(type default)
			)
			(layer "B.SilkS")
		)
		(fp_line
			(start 4.533392 2.249932)
			(end 4.533392 -2.249932)
			(stroke
				(width 0.1524)
				(type default)
			)
			(layer "B.SilkS")
		)
		(fp_line
			(start -4.533392 -2.249932)
			(end -4.533392 2.249932)
			(stroke
				(width 0.1524)
				(type default)
			)
			(layer "B.SilkS")
		)
		(fp_line
			(start 4.533392 -2.249932)
			(end -4.533392 -2.249932)
			(stroke
				(width 0.1524)
				(type default)
			)
			(layer "B.SilkS")
		)
		(fp_rect
			(start 5.39242 2.326132)
			(end 4.533392 -2.326132)
			(stroke
				(width 0)
				(type default)
			)
			(fill yes)
			(layer "B.SilkS")
		)
		(fp_line
			(start -3.750056 2.249932)
			(end 3.750056 2.249932)
			(stroke
				(width 0.1)
				(type default)
			)
			(layer "B.Fab")
		)
		(fp_line
			(start 3.750056 2.249932)
			(end 3.750056 -2.249932)
			(stroke
				(width 0.1)
				(type default)
			)
			(layer "B.Fab")
		)
		(fp_line
			(start -3.750056 -2.249932)
			(end -3.750056 2.249932)
			(stroke
				(width 0.1)
				(type default)
			)
			(layer "B.Fab")
		)
		(fp_line
			(start 3.750056 -2.249932)
			(end -3.750056 -2.249932)
			(stroke
				(width 0.1)
				(type default)
			)
			(layer "B.Fab")
		)
		(fp_text user "+"
			(at 6.322314 0.786384 180)
			(unlocked yes)
			(layer "B.SilkS")
			(effects
				(font
					(size 1.905 1.4224)
					(thickness 0.1524)
				)
				(justify left mirror)
			)
		)
		(fp_text user "-"
			(at -4.618228 0.045466 270)
			(unlocked yes)
			(layer "B.SilkS")
			(effects
				(font
					(size 1.905 1.4224)
					(thickness 0.1524)
				)
				(justify left mirror)
			)
		)
		(fp_text user "+"
			(at 6.322314 0.786384 180)
			(unlocked yes)
			(layer "B.Fab")
			(effects
				(font
					(size 1.905 1.4224)
					(thickness 0.1524)
				)
				(justify left mirror)
			)
		)
		(fp_text user "-"
			(at -4.8514 -0.14605 270)
			(unlocked yes)
			(layer "B.Fab")
			(effects
				(font
					(size 1.905 1.4224)
					(thickness 0.1524)
				)
				(justify left mirror)
			)
		)
		(pad "1" smd rect
			(at 3.199892 0 90)
			(size 2.413 2.8194)
			(layers "B.Cu" "B.Mask" "B.Paste")
			(net "PVDD11_S3_P0")
		)
		(pad "2" smd rect
			(at -3.199892 0 90)
			(size 2.413 2.8194)
			(layers "B.Cu" "B.Mask" "B.Paste")
			(net "GND")
		)
	)
	(footprint ""
		(layer "B.Cu")
		(at 367.595658 -139.780772 -90)
		(property "Reference" "PQ17"
			(at -0.07112 -2.670048 270)
			(unlocked yes)
			(layer "B.SilkS")
			(effects
				(font
					(size 0.7874 0.5842)
					(thickness 0.1524)
				)
				(justify mirror)
			)
		)
		(property "Value" ""
			(at 0 0 90)
			(layer "B.Fab")
			(effects
				(font
					(size 1.27 1.27)
				)
				(justify mirror)
			)
		)
		(duplicate_pad_numbers_are_jumpers no)
		(fp_line
			(start -1.949958 1.610106)
			(end 1.949958 1.610106)
			(stroke
				(width 0.1524)
				(type default)
			)
			(layer "B.SilkS")
		)
		(fp_line
			(start 1.949958 1.610106)
			(end 1.949958 -1.610106)
			(stroke
				(width 0.1524)
				(type default)
			)
			(layer "B.SilkS")
		)
		(fp_line
			(start -1.949958 -1.560068)
			(end -1.949958 1.610106)
			(stroke
				(width 0.1524)
				(type default)
			)
			(layer "B.SilkS")
		)
		(fp_line
			(start 1.949958 -1.610106)
			(end -1.949958 -1.610106)
			(stroke
				(width 0.1524)
				(type default)
			)
			(layer "B.SilkS")
		)
		(fp_line
			(start -0.750062 1.560068)
			(end 0.750062 1.560068)
			(stroke
				(width 0.1)
				(type default)
			)
			(layer "B.Fab")
		)
		(fp_line
			(start 0.750062 1.560068)
			(end 0.750062 -1.560068)
			(stroke
				(width 0.1)
				(type default)
			)
			(layer "B.Fab")
		)
		(fp_line
			(start -0.750062 -1.560068)
			(end -0.750062 1.560068)
			(stroke
				(width 0.1)
				(type default)
			)
			(layer "B.Fab")
		)
		(fp_line
			(start 0.750062 -1.560068)
			(end -0.750062 -1.560068)
			(stroke
				(width 0.1)
				(type default)
			)
			(layer "B.Fab")
		)
		(pad "D" smd rect
			(at -1.100074 0 180)
			(size 1.016 1.4224)
			(layers "B.Cu" "B.Mask" "B.Paste")
			(net "PVDDCR_SOC_P0_EN_GD")
		)
		(pad "G" smd rect
			(at 1.100074 -0.94996 180)
			(size 1.016 1.4224)
			(layers "B.Cu" "B.Mask" "B.Paste")
			(net "PVDDCR_SOC_P0_EN_RC")
		)
		(pad "S" smd rect
			(at 1.100074 0.94996 180)
			(size 1.016 1.4224)
			(layers "B.Cu" "B.Mask" "B.Paste")
			(net "GND")
		)
	)
	(footprint ""
		(layer "B.Cu")
		(at 109.095794 -385.58216 180)
		(property "Reference" "R918"
			(at 0 0 0)
			(layer "B.SilkS")
			(hide yes)
			(effects
				(font
					(size 1.27 1.27)
				)
				(justify mirror)
			)
		)
		(property "Value" ""
			(at 0 0 0)
			(layer "B.Fab")
			(effects
				(font
					(size 1.27 1.27)
				)
				(justify mirror)
			)
		)
		(duplicate_pad_numbers_are_jumpers no)
		(fp_line
			(start 0.32512 0.175006)
			(end 0.32512 -0.175006)
			(stroke
				(width 0.1)
				(type default)
			)
			(layer "B.Fab")
		)
		(fp_line
			(start 0.32512 -0.175006)
			(end -0.32512 -0.175006)
			(stroke
				(width 0.1)
				(type default)
			)
			(layer "B.Fab")
		)
		(fp_line
			(start -0.32512 0.175006)
			(end 0.32512 0.175006)
			(stroke
				(width 0.1)
				(type default)
			)
			(layer "B.Fab")
		)
		(fp_line
			(start -0.32512 -0.175006)
			(end -0.32512 0.175006)
			(stroke
				(width 0.1)
				(type default)
			)
			(layer "B.Fab")
		)
		(pad "1" smd rect
			(at 0.2667 0)
			(size 0.3048 0.381)
			(layers "B.Cu" "B.Mask" "B.Paste")
			(net "P1V8_CPU1_RT_1D")
		)
		(pad "2" smd rect
			(at -0.2667 0 180)
			(size 0.3048 0.381)
			(layers "B.Cu" "B.Mask" "B.Paste")
			(net "TEST0_RT_CPU1_P3")
		)
	)
)
